(kicad_pcb
	(version 20260206)
	(generator "pcbnew")
	(generator_version "10.0")
	(general
		(thickness 1.21888)
		(legacy_teardrops no)
	)
	(paper "A4")
	(title_block
		(title "timecard-v9 — TimeCard-DC-V9_EXP.PcbDoc")
		(comment 1 "Time Appliance Project (Time Card) / footprints 131-138 of 402")
	)
	(layers
		(0 "F.Cu" signal "TOP")
		(4 "In1.Cu" signal "SGND")
		(6 "In2.Cu" signal "IN1")
		(8 "In3.Cu" signal "IN2")
		(10 "In4.Cu" signal "SGND1")
		(2 "B.Cu" signal "BOTTOM")
		(9 "F.Adhes" user "F.Adhesive")
		(11 "B.Adhes" user "B.Adhesive")
		(13 "F.Paste" user "Top Paste")
		(15 "B.Paste" user "Bottom Paste")
		(5 "F.SilkS" user "Top Overlay")
		(7 "B.SilkS" user "Bottom Overlay")
		(1 "F.Mask" user "Top Solder")
		(3 "B.Mask" user "Bottom Solder")
		(17 "Dwgs.User" user "User.Drawings")
		(19 "Cmts.User" user "User.Comments")
		(21 "Eco1.User" user "User.Eco1")
		(23 "Eco2.User" user "User.Eco2")
		(25 "Edge.Cuts" user)
		(27 "Margin" user)
		(31 "F.CrtYd" user "Top Courtyard")
		(29 "B.CrtYd" user "Bottom Courtyard")
		(35 "F.Fab" user "Top Component Center")
		(33 "B.Fab" user "Bottom Component Center")
	)
	(footprint "Vault:FP-RUT0012A-MFG"
		(layer "F.Cu")
		(at 153.5216 129.7162)
		(property "Reference" "U22"
			(at -2.37291 -2.371569 0)
			(unlocked yes)
			(layer "F.SilkS")
			(effects
				(font
					(size 0.762 0.762)
					(thickness 0.2286)
				)
			)
		)
		(property "Value" "TMUX1072RUTR"
			(at 7.426665 3.164071 0)
			(unlocked yes)
			(layer "F.SilkS")
			(hide yes)
			(effects
				(font
					(size 0.762 0.762)
					(thickness 0.2286)
				)
			)
		)
		(sheetname "09-USBUart_PPSMUX_UARTMUX")
		(sheetfile "09-USBUart_PPSMUX_UARTMUX.kicad_sch")
		(duplicate_pad_numbers_are_jumpers no)
		(fp_line
			(start -0.9 -1.525)
			(end 0.9 -1.525)
			(stroke
				(width 0.2)
				(type solid)
			)
			(layer "F.SilkS")
		)
		(fp_line
			(start -0.9 1.525)
			(end 0.9 1.525)
			(stroke
				(width 0.2)
				(type solid)
			)
			(layer "F.SilkS")
		)
		(fp_circle
			(center -1.575 -0.8)
			(end -1.575 -0.925)
			(stroke
				(width 0.25)
				(type solid)
			)
			(fill no)
			(layer "F.SilkS")
		)
		(fp_rect
			(start -0.85 -0.3)
			(end -0.35 -0.5)
			(stroke
				(width 0)
				(type default)
			)
			(fill yes)
			(layer "F.Paste")
		)
		(fp_rect
			(start -0.85 0.1)
			(end -0.35 -0.1)
			(stroke
				(width 0)
				(type default)
			)
			(fill yes)
			(layer "F.Paste")
		)
		(fp_rect
			(start -0.85 0.5)
			(end -0.35 0.3)
			(stroke
				(width 0)
				(type default)
			)
			(fill yes)
			(layer "F.Paste")
		)
		(fp_rect
			(start -0.85 0.9)
			(end -0.35 0.7)
			(stroke
				(width 0)
				(type default)
			)
			(fill yes)
			(layer "F.Paste")
		)
		(fp_rect
			(start -0.1 -0.5)
			(end 0.1 -1)
			(stroke
				(width 0)
				(type default)
			)
			(fill yes)
			(layer "F.Paste")
		)
		(fp_rect
			(start -0.1 1)
			(end 0.1 0.5)
			(stroke
				(width 0)
				(type default)
			)
			(fill yes)
			(layer "F.Paste")
		)
		(fp_rect
			(start 0.35 -0.7)
			(end 0.85 -0.9)
			(stroke
				(width 0)
				(type default)
			)
			(fill yes)
			(layer "F.Paste")
		)
		(fp_rect
			(start 0.35 -0.3)
			(end 0.85 -0.5)
			(stroke
				(width 0)
				(type default)
			)
			(fill yes)
			(layer "F.Paste")
		)
		(fp_rect
			(start 0.35 0.1)
			(end 0.85 -0.1)
			(stroke
				(width 0)
				(type default)
			)
			(fill yes)
			(layer "F.Paste")
		)
		(fp_rect
			(start 0.35 0.5)
			(end 0.85 0.3)
			(stroke
				(width 0)
				(type default)
			)
			(fill yes)
			(layer "F.Paste")
		)
		(fp_rect
			(start 0.35 0.9)
			(end 0.85 0.7)
			(stroke
				(width 0)
				(type default)
			)
			(fill yes)
			(layer "F.Paste")
		)
		(fp_poly
			(pts
				(xy -0.5 -1) (xy -0.35 -1) (xy -0.35 -0.7) (xy -0.85 -0.7) (xy -0.85 -0.9) (xy -0.5 -0.9)
			)
			(stroke
				(width 0)
				(type default)
			)
			(fill yes)
			(layer "F.Paste")
		)
		(fp_line
			(start -1.05 -1.2)
			(end 1.05 -1.2)
			(stroke
				(width 0.2)
				(type solid)
			)
			(layer "F.CrtYd")
		)
		(fp_line
			(start -1.05 1.2)
			(end -1.05 -1.2)
			(stroke
				(width 0.2)
				(type solid)
			)
			(layer "F.CrtYd")
		)
		(fp_line
			(start -1.05 1.2)
			(end 1.05 1.2)
			(stroke
				(width 0.2)
				(type solid)
			)
			(layer "F.CrtYd")
		)
		(fp_line
			(start 1.05 1.2)
			(end 1.05 -1.2)
			(stroke
				(width 0.2)
				(type solid)
			)
			(layer "F.CrtYd")
		)
		(fp_line
			(start -1.05 -1.2)
			(end 1.05 -1.2)
			(stroke
				(width 0.2)
				(type solid)
			)
			(layer "F.Fab")
		)
		(fp_line
			(start -1.05 1.2)
			(end -1.05 -1.2)
			(stroke
				(width 0.2)
				(type solid)
			)
			(layer "F.Fab")
		)
		(fp_line
			(start -1.05 1.2)
			(end 1.05 1.2)
			(stroke
				(width 0.2)
				(type solid)
			)
			(layer "F.Fab")
		)
		(fp_line
			(start -0.5 0)
			(end 0.5 0)
			(stroke
				(width 0.1)
				(type solid)
			)
			(layer "F.Fab")
		)
		(fp_line
			(start 0 0.5)
			(end 0 -0.5)
			(stroke
				(width 0.1)
				(type solid)
			)
			(layer "F.Fab")
		)
		(fp_line
			(start 1.05 1.2)
			(end 1.05 -1.2)
			(stroke
				(width 0.2)
				(type solid)
			)
			(layer "F.Fab")
		)
		(fp_text user "${REFERENCE}"
			(at -0.00001 0.09602 0)
			(unlocked yes)
			(layer "F.Fab")
			(effects
				(font
					(face "Arial")
					(size 0.63 0.63)
					(thickness 0.1)
				)
				(justify left bottom)
			)
		)
		(pad "" smd custom
			(at -0.5 -1.1)
			(size 0.000001 0.000001)
			(layers "F.Cu" "F.Mask")
			(solder_mask_margin 0)
			(thermal_bridge_angle 90)
			(options
				(clearance outline)
				(anchor circle)
			)
			(primitives
				(gr_poly
					(pts
						(xy 0 0) (xy 0.15 0) (xy 0.15 0.4) (xy -0.45 0.4) (xy -0.45 0.2) (xy 0 0.2)
					)
					(width 0)
					(fill yes)
				)
			)
		)
		(pad "1" smd circle
			(at -0.45 -0.8)
			(size 0.18 0.18)
			(layers "F.Cu" "F.Mask" "F.Paste")
			(net "DIP_SW_UART_SEL")
			(solder_mask_margin 0)
			(solder_paste_margin -1000)
			(thermal_bridge_angle 90)
		)
		(pad "2" smd rect
			(at -0.65 -0.4)
			(size 0.6 0.2)
			(layers "F.Cu" "F.Mask" "F.Paste")
			(net "NetR91_2")
			(solder_mask_margin 0)
			(solder_paste_margin -1000)
		)
		(pad "3" smd rect
			(at -0.65 0)
			(size 0.6 0.2)
			(layers "F.Cu" "F.Mask" "F.Paste")
			(net "GND")
			(solder_mask_margin 0)
			(solder_paste_margin -1000)
		)
		(pad "4" smd rect
			(at -0.65 0.4)
			(size 0.6 0.2)
			(layers "F.Cu" "F.Mask" "F.Paste")
			(net "NetR93_2")
			(solder_mask_margin 0)
			(solder_paste_margin -1000)
		)
		(pad "5" smd rect
			(at -0.65 0.8)
			(size 0.6 0.2)
			(layers "F.Cu" "F.Mask" "F.Paste")
			(net "DIP_SW_UART_SEL")
			(solder_mask_margin 0)
			(solder_paste_margin -1000)
		)
		(pad "6" smd rect
			(at 0 0.8)
			(size 0.2 0.6)
			(layers "F.Cu" "F.Mask" "F.Paste")
			(net "GND")
			(solder_mask_margin 0)
			(solder_paste_margin -1000)
		)
		(pad "7" smd rect
			(at 0.65 0.8)
			(size 0.6 0.2)
			(layers "F.Cu" "F.Mask" "F.Paste")
			(net "GPS2_RX")
			(solder_mask_margin 0)
			(solder_paste_margin -1000)
		)
		(pad "8" smd rect
			(at 0.65 0.4)
			(size 0.6 0.2)
			(layers "F.Cu" "F.Mask" "F.Paste")
			(net "NetR92_2")
			(solder_mask_margin 0)
			(solder_paste_margin -1000)
		)
		(pad "9" smd rect
			(at 0.65 0)
			(size 0.6 0.2)
			(layers "F.Cu" "F.Mask" "F.Paste")
			(net "GNSS2_P3V3")
			(solder_mask_margin 0)
			(solder_paste_margin -1000)
		)
		(pad "10" smd rect
			(at 0.65 -0.4)
			(size 0.6 0.2)
			(layers "F.Cu" "F.Mask" "F.Paste")
			(net "NetR90_2")
			(solder_mask_margin 0)
			(solder_paste_margin -1000)
		)
		(pad "11" smd rect
			(at 0.65 -0.8)
			(size 0.6 0.2)
			(layers "F.Cu" "F.Mask" "F.Paste")
			(net "GPS2_TX")
			(solder_mask_margin 0)
			(solder_paste_margin -1000)
		)
		(pad "12" smd rect
			(at 0 -0.8)
			(size 0.2 0.6)
			(layers "F.Cu" "F.Mask" "F.Paste")
			(net "GND")
			(solder_mask_margin 0)
			(solder_paste_margin -1000)
		)
	)
	(footprint "Vault:CAPC1608X87X45ML20T05"
		(layer "F.Cu")
		(at 227.5216 65.5162 -90)
		(property "Reference" "C2"
			(at -1.8 -0.393345 90)
			(unlocked yes)
			(layer "F.SilkS")
			(effects
				(font
					(size 0.762 0.762)
					(thickness 0.2286)
				)
				(justify left bottom)
			)
		)
		(property "Value" "0.1uF"
			(at 1.525445 1.1493 0)
			(unlocked yes)
			(layer "F.SilkS")
			(hide yes)
			(effects
				(font
					(size 0.762 0.762)
					(thickness 0.2286)
				)
				(justify left bottom)
			)
		)
		(sheetname "03-POWER")
		(sheetfile "03-POWER.kicad_sch")
		(duplicate_pad_numbers_are_jumpers no)
		(pad "1" smd rect
			(at -0.7 0)
			(size 1.1 1.05)
			(layers "F.Cu" "F.Mask" "F.Paste")
			(net "GND")
		)
		(pad "2" smd rect
			(at 0.7 0)
			(size 1.1 1.05)
			(layers "F.Cu" "F.Mask" "F.Paste")
			(net "+12V")
		)
	)
	(footprint "Miscellaneous Connectors:HDR2X6_CEN"
		(layer "F.Cu")
		(at 226.9216 80.0562 -90)
		(property "Reference" "P3"
			(at 5.031395 1.873079 90)
			(unlocked yes)
			(layer "F.SilkS")
			(effects
				(font
					(size 0.762 0.762)
					(thickness 0.2286)
				)
			)
		)
		(property "Value" "EXT GPIO"
			(at -4.281671 2.296855 180)
			(unlocked yes)
			(layer "F.SilkS")
			(hide yes)
			(effects
				(font
					(size 0.762 0.762)
					(thickness 0.2286)
				)
			)
		)
		(sheetname "05-GPS_IMU_SENSORS")
		(sheetfile "05-GPS_IMU_SENSORS.kicad_sch")
		(duplicate_pad_numbers_are_jumpers no)
		(fp_line
			(start -1.27 1.27)
			(end -1.27 -3.81)
			(stroke
				(width 0.2)
				(type solid)
			)
			(layer "F.SilkS")
		)
		(fp_line
			(start 13.97 1.27)
			(end -1.27 1.27)
			(stroke
				(width 0.2)
				(type solid)
			)
			(layer "F.SilkS")
		)
		(fp_line
			(start 13.97 1.27)
			(end 13.97 -3.81)
			(stroke
				(width 0.2)
				(type solid)
			)
			(layer "F.SilkS")
		)
		(fp_line
			(start 13.97 -3.81)
			(end -1.27 -3.81)
			(stroke
				(width 0.2)
				(type solid)
			)
			(layer "F.SilkS")
		)
		(fp_text user "6"
			(at 10.56 2.655575 270)
			(unlocked yes)
			(layer "F.SilkS")
			(effects
				(font
					(size 1.27 1.27)
					(thickness 0.2032)
				)
				(justify left bottom)
			)
		)
		(fp_text user "1"
			(at -2.14 0.855575 270)
			(unlocked yes)
			(layer "F.SilkS")
			(effects
				(font
					(size 1.27 1.27)
					(thickness 0.2032)
				)
				(justify left bottom)
			)
		)
		(fp_text user "7"
			(at -2.54 -1.876425 270)
			(unlocked yes)
			(layer "F.SilkS")
			(effects
				(font
					(size 1.27 1.27)
					(thickness 0.2032)
				)
				(justify left bottom)
			)
		)
		(fp_text user "12"
			(at 11.68946 -3.654425 270)
			(unlocked yes)
			(layer "F.SilkS")
			(effects
				(font
					(size 1.27 1.27)
					(thickness 0.2032)
				)
				(justify left bottom)
			)
		)
		(pad "1" thru_hole rect
			(at 0 0 270)
			(size 1.5 1.5)
			(drill 0.9)
			(layers "*.Cu" "*.Mask")
			(remove_unused_layers no)
			(net "EXT_GPIO_1")
		)
		(pad "2" thru_hole circle
			(at 2.54 0 270)
			(size 1.5 1.5)
			(drill 0.9)
			(layers "*.Cu" "*.Mask")
			(remove_unused_layers no)
			(net "EXT_GPIO_2")
			(thermal_bridge_angle 90)
		)
		(pad "3" thru_hole circle
			(at 5.08 0 270)
			(size 1.5 1.5)
			(drill 0.9)
			(layers "*.Cu" "*.Mask")
			(remove_unused_layers no)
			(net "EXT_GPIO_3")
			(thermal_bridge_angle 90)
		)
		(pad "4" thru_hole circle
			(at 7.62 0 270)
			(size 1.5 1.5)
			(drill 0.9)
			(layers "*.Cu" "*.Mask")
			(remove_unused_layers no)
			(net "EXT_GPIO_4")
			(thermal_bridge_angle 90)
		)
		(pad "5" thru_hole circle
			(at 10.16 0 270)
			(size 1.5 1.5)
			(drill 0.9)
			(layers "*.Cu" "*.Mask")
			(remove_unused_layers no)
			(net "GND")
			(thermal_bridge_angle 90)
		)
		(pad "6" thru_hole circle
			(at 12.7 0 270)
			(size 1.5 1.5)
			(drill 0.9)
			(layers "*.Cu" "*.Mask")
			(remove_unused_layers no)
			(net "+3.3V")
			(thermal_bridge_angle 90)
		)
		(pad "7" thru_hole circle
			(at 0 -2.54 270)
			(size 1.5 1.5)
			(drill 0.9)
			(layers "*.Cu" "*.Mask")
			(remove_unused_layers no)
			(net "EXT_GPIO_7")
			(thermal_bridge_angle 90)
		)
		(pad "8" thru_hole circle
			(at 2.54 -2.54 270)
			(size 1.5 1.5)
			(drill 0.9)
			(layers "*.Cu" "*.Mask")
			(remove_unused_layers no)
			(net "EXT_GPIO_8")
			(thermal_bridge_angle 90)
		)
		(pad "9" thru_hole circle
			(at 5.08 -2.54 270)
			(size 1.5 1.5)
			(drill 0.9)
			(layers "*.Cu" "*.Mask")
			(remove_unused_layers no)
			(net "EXT_GPIO_9")
			(thermal_bridge_angle 90)
		)
		(pad "10" thru_hole circle
			(at 7.62 -2.54 270)
			(size 1.5 1.5)
			(drill 0.9)
			(layers "*.Cu" "*.Mask")
			(remove_unused_layers no)
			(net "EXT_GPIO_10")
			(thermal_bridge_angle 90)
		)
		(pad "11" thru_hole circle
			(at 10.16 -2.54 270)
			(size 1.5 1.5)
			(drill 0.9)
			(layers "*.Cu" "*.Mask")
			(remove_unused_layers no)
			(net "GND")
			(thermal_bridge_angle 90)
		)
		(pad "12" thru_hole circle
			(at 12.7 -2.54 270)
			(size 1.5 1.5)
			(drill 0.9)
			(layers "*.Cu" "*.Mask")
			(remove_unused_layers no)
			(net "+3.3V")
			(thermal_bridge_angle 90)
		)
	)
	(footprint "Vault:RESC3116X65X50ML20T20"
		(layer "F.Cu")
		(at 140.7716 87.8662)
		(property "Reference" "R46"
			(at 4.0786 -0.023069 0)
			(unlocked yes)
			(layer "F.SilkS")
			(effects
				(font
					(size 0.762 0.762)
					(thickness 0.2286)
				)
			)
		)
		(property "Value" "DNI_0_5%_1206"
			(at 7.27402 3.291071 0)
			(unlocked yes)
			(layer "F.SilkS")
			(hide yes)
			(effects
				(font
					(size 0.762 0.762)
					(thickness 0.2286)
				)
			)
		)
		(sheetname "06-MAC")
		(sheetfile "06-MAC.kicad_sch")
		(duplicate_pad_numbers_are_jumpers no)
		(fp_line
			(start -0.35 -0.85)
			(end 0.35 -0.85)
			(stroke
				(width 0.2)
				(type solid)
			)
			(layer "F.SilkS")
		)
		(fp_line
			(start -0.35 0.85)
			(end 0.35 0.85)
			(stroke
				(width 0.2)
				(type solid)
			)
			(layer "F.SilkS")
		)
		(pad "1" smd rect
			(at -1.475 0 90)
			(size 1.9 1.45)
			(layers "F.Cu" "F.Mask" "F.Paste")
			(net "MAC_VCC")
		)
		(pad "2" smd rect
			(at 1.475 0 90)
			(size 1.9 1.45)
			(layers "F.Cu" "F.Mask" "F.Paste")
			(net "+12V")
		)
	)
	(footprint "Vault:RESC1005X40X25NL10T10"
		(layer "F.Cu")
		(at 175.5216 115.6162)
		(property "Reference" "R115"
			(at 2.7032 0.126931 0)
			(unlocked yes)
			(layer "F.SilkS")
			(effects
				(font
					(size 0.762 0.762)
					(thickness 0.2032)
				)
			)
		)
		(property "Value" "4.7K_1%_0402"
			(at -2.732271 8.747465 270)
			(unlocked yes)
			(layer "F.SilkS")
			(hide yes)
			(effects
				(font
					(size 0.762 0.762)
					(thickness 0.2032)
				)
			)
		)
		(sheetname "08-DIPSwitches_I2C")
		(sheetfile "08-DIPSwitches_I2C.kicad_sch")
		(duplicate_pad_numbers_are_jumpers no)
		(pad "1" smd rect
			(at -0.425 0 90)
			(size 0.6 0.65)
			(layers "F.Cu" "F.Mask" "F.Paste")
			(net "ANADC_I2C_SDA")
		)
		(pad "2" smd rect
			(at 0.425 0 90)
			(size 0.6 0.65)
			(layers "F.Cu" "F.Mask" "F.Paste")
			(net "+3.3V")
		)
	)
	(footprint "Vault:RESC1005X40X25LL05T05"
		(layer "F.Cu")
		(at 113.2216 68.9162 180)
		(property "Reference" "R130"
			(at -0.326931 2.4032 90)
			(unlocked yes)
			(layer "F.SilkS")
			(effects
				(font
					(size 0.762 0.762)
					(thickness 0.2032)
				)
			)
		)
		(property "Value" "DNI_0_1%_0402"
			(at -2.579871 9.56002 90)
			(unlocked yes)
			(layer "F.SilkS")
			(hide yes)
			(effects
				(font
					(size 0.762 0.762)
					(thickness 0.2032)
				)
			)
		)
		(sheetname "10-M2_GPS")
		(sheetfile "10-M2_GPS.kicad_sch")
		(duplicate_pad_numbers_are_jumpers no)
		(pad "1" smd rect
			(at -0.4 0 270)
			(size 0.45 0.45)
			(layers "F.Cu" "F.Mask" "F.Paste")
			(net "NetJ44_35")
		)
		(pad "2" smd rect
			(at 0.4 0 270)
			(size 0.45 0.45)
			(layers "F.Cu" "F.Mask" "F.Paste")
			(net "M2_GPS1_TP1")
		)
	)
	(footprint "SA53:SolderSocket"
		(locked yes)
		(layer "F.Cu")
		(at 122.4216 140.0162 90)
		(property "Reference" "SKT3"
			(at -3.426921 2.1286 0)
			(unlocked yes)
			(layer "F.SilkS")
			(effects
				(font
					(size 0.762 0.762)
					(thickness 0.2286)
				)
			)
		)
		(property "Value" "0332-0-43-80-18-27-10-0"
			(at -2.910071 16.1362 0)
			(unlocked yes)
			(layer "F.SilkS")
			(hide yes)
			(effects
				(font
					(size 0.762 0.762)
					(thickness 0.2286)
				)
			)
		)
		(sheetname "06-MAC")
		(sheetfile "06-MAC.kicad_sch")
		(duplicate_pad_numbers_are_jumpers no)
		(pad "1" thru_hole circle
			(at 0 0 90)
			(size 2.54 2.54)
			(drill 2.0066)
			(layers "*.Cu" "*.Mask")
			(remove_unused_layers no)
			(net "MAC_RX")
			(thermal_bridge_angle 90)
		)
	)
	(footprint "Vault:RESC3116X65X50ML20T20"
		(layer "F.Cu")
		(at 140.7716 93.8662)
		(property "Reference" "R47"
			(at 3.9286 -0.073069 0)
			(unlocked yes)
			(layer "F.SilkS")
			(effects
				(font
					(size 0.762 0.762)
					(thickness 0.2286)
				)
			)
		)
		(property "Value" "DNI_0_5%_1206"
			(at 7.27402 3.291071 0)
			(unlocked yes)
			(layer "F.SilkS")
			(hide yes)
			(effects
				(font
					(size 0.762 0.762)
					(thickness 0.2286)
				)
			)
		)
		(sheetname "06-MAC")
		(sheetfile "06-MAC.kicad_sch")
		(duplicate_pad_numbers_are_jumpers no)
		(fp_line
			(start -0.35 -0.85)
			(end 0.35 -0.85)
			(stroke
				(width 0.2)
				(type solid)
			)
			(layer "F.SilkS")
		)
		(fp_line
			(start -0.35 0.85)
			(end 0.35 0.85)
			(stroke
				(width 0.2)
				(type solid)
			)
			(layer "F.SilkS")
		)
		(pad "1" smd rect
			(at -1.475 0 90)
			(size 1.9 1.45)
			(layers "F.Cu" "F.Mask" "F.Paste")
			(net "MAC_VCC")
		)
		(pad "2" smd rect
			(at 1.475 0 90)
			(size 1.9 1.45)
			(layers "F.Cu" "F.Mask" "F.Paste")
			(net "+3.3V")
		)
	)
)
